(kicad_pcb
	(version 20260206)
	(generator "pcbnew")
	(generator_version "10.0")
	(general
		(thickness 1.21888)
		(legacy_teardrops no)
	)
	(paper "A4")
	(title_block
		(title "timecard-v8 — TimeCard-DC-V8_EXP.PcbDoc")
		(comment 1 "Time Appliance Project (Time Card) / footprints 52-63 of 288")
	)
	(layers
		(0 "F.Cu" signal "TOP")
		(4 "In1.Cu" signal "SGND")
		(6 "In2.Cu" signal "IN1")
		(8 "In3.Cu" signal "IN2")
		(10 "In4.Cu" signal "SGND1")
		(2 "B.Cu" signal "BOTTOM")
		(9 "F.Adhes" user "F.Adhesive")
		(11 "B.Adhes" user "B.Adhesive")
		(13 "F.Paste" user "Top Paste")
		(15 "B.Paste" user "Bottom Paste")
		(5 "F.SilkS" user "Top Overlay")
		(7 "B.SilkS" user "Bottom Overlay")
		(1 "F.Mask" user "Top Solder")
		(3 "B.Mask" user "Bottom Solder")
		(17 "Dwgs.User" user "User.Drawings")
		(19 "Cmts.User" user "User.Comments")
		(21 "Eco1.User" user "User.Eco1")
		(23 "Eco2.User" user "User.Eco2")
		(25 "Edge.Cuts" user)
		(27 "Margin" user)
		(31 "F.CrtYd" user "Top Courtyard")
		(29 "B.CrtYd" user "Bottom Courtyard")
		(35 "F.Fab" user "Top Component Center")
		(33 "B.Fab" user "Bottom Component Center")
	)
	(footprint "Vault:FP-LTST-C191TBKT-MFG"
		(layer "F.Cu")
		(at 71.6261 52.1162 90)
		(property "Reference" "D9"
			(at -6.771395 -0.223079 90)
			(unlocked yes)
			(layer "F.SilkS")
			(effects
				(font
					(size 0.762 0.762)
					(thickness 0.2286)
				)
			)
		)
		(property "Value" "BLUE"
			(at 1.2818 2.452871 90)
			(unlocked yes)
			(layer "F.SilkS")
			(hide yes)
			(effects
				(font
					(size 0.762 0.762)
					(thickness 0.2286)
				)
			)
		)
		(sheetname "USER_IO_STATUS")
		(sheetfile "USER_IO_STATUS.kicad_sch")
		(duplicate_pad_numbers_are_jumpers no)
		(fp_line
			(start -0.85 -0.8)
			(end 0.85 -0.8)
			(stroke
				(width 0.2)
				(type solid)
			)
			(layer "F.SilkS")
		)
		(fp_line
			(start -0.85 0.8)
			(end 0.85 0.8)
			(stroke
				(width 0.2)
				(type solid)
			)
			(layer "F.SilkS")
		)
		(fp_circle
			(center -1.75 0)
			(end -1.625 0)
			(stroke
				(width 0.25)
				(type solid)
			)
			(fill no)
			(layer "F.SilkS")
		)
		(fp_line
			(start 1.25 -0.55)
			(end 1.25 0.55)
			(stroke
				(width 0.2)
				(type solid)
			)
			(layer "F.CrtYd")
		)
		(fp_line
			(start -1.25 -0.55)
			(end 1.25 -0.55)
			(stroke
				(width 0.2)
				(type solid)
			)
			(layer "F.CrtYd")
		)
		(fp_line
			(start -1.25 -0.55)
			(end -1.25 0.55)
			(stroke
				(width 0.2)
				(type solid)
			)
			(layer "F.CrtYd")
		)
		(fp_line
			(start -1.25 0.55)
			(end 1.25 0.55)
			(stroke
				(width 0.2)
				(type solid)
			)
			(layer "F.CrtYd")
		)
		(fp_line
			(start 1.25 -0.55)
			(end 1.25 0.55)
			(stroke
				(width 0.2)
				(type solid)
			)
			(layer "F.Fab")
		)
		(fp_line
			(start -1.25 -0.55)
			(end 1.25 -0.55)
			(stroke
				(width 0.2)
				(type solid)
			)
			(layer "F.Fab")
		)
		(fp_line
			(start -1.25 -0.55)
			(end -1.25 0.55)
			(stroke
				(width 0.2)
				(type solid)
			)
			(layer "F.Fab")
		)
		(fp_line
			(start 0 -0.5)
			(end 0 0.5)
			(stroke
				(width 0.1)
				(type solid)
			)
			(layer "F.Fab")
		)
		(fp_line
			(start -0.5 0)
			(end 0.5 0)
			(stroke
				(width 0.1)
				(type solid)
			)
			(layer "F.Fab")
		)
		(fp_line
			(start -1.25 0.55)
			(end 1.25 0.55)
			(stroke
				(width 0.2)
				(type solid)
			)
			(layer "F.Fab")
		)
		(fp_text user "${REFERENCE}"
			(at 0 0.28425 90)
			(unlocked yes)
			(layer "F.Fab")
			(effects
				(font
					(face "Arial")
					(size 0.63 0.63)
					(thickness 0.1)
				)
				(justify left bottom)
			)
		)
		(pad "1" smd rect
			(at -0.75 0 90)
			(size 0.8 0.8)
			(layers "F.Cu" "F.Mask" "F.Paste")
			(net "NetD9_1")
			(solder_mask_margin 0)
			(solder_paste_margin 0)
		)
		(pad "2" smd rect
			(at 0.75 0 90)
			(size 0.8 0.8)
			(layers "F.Cu" "F.Mask" "F.Paste")
			(net "+3.3V")
			(solder_mask_margin 0)
			(solder_paste_margin 0)
		)
	)
	(footprint "Vault:RESC1005X40X25LL05T05"
		(layer "F.Cu")
		(at 80.3261 85.0162 180)
		(property "Reference" "R110"
			(at 2.9714 -0.426931 0)
			(unlocked yes)
			(layer "F.SilkS")
			(effects
				(font
					(size 0.762 0.762)
					(thickness 0.2286)
				)
			)
		)
		(property "Value" "DNI_4.7K_0402"
			(at -2.352802 9.48386 90)
			(unlocked yes)
			(layer "F.SilkS")
			(hide yes)
			(effects
				(font
					(size 1.524 1.524)
					(thickness 0.254)
				)
			)
		)
		(sheetname "USER_IO_STATUS")
		(sheetfile "USER_IO_STATUS.kicad_sch")
		(duplicate_pad_numbers_are_jumpers no)
		(pad "1" smd rect
			(at -0.4 0 270)
			(size 0.45 0.45)
			(layers "F.Cu" "F.Mask" "F.Paste")
			(net "NetR108_2")
		)
		(pad "2" smd rect
			(at 0.4 0 270)
			(size 0.45 0.45)
			(layers "F.Cu" "F.Mask" "F.Paste")
			(net "GND")
		)
	)
	(footprint "Vault:RESC1005X40X25NL05T05"
		(layer "F.Cu")
		(at 209.3761 82.1162)
		(property "Reference" "R103"
			(at 3.03687 0.059321 0)
			(unlocked yes)
			(layer "F.SilkS")
			(effects
				(font
					(size 0.762 0.762)
					(thickness 0.2286)
				)
			)
		)
		(property "Value" "DNI_27_1%_0402"
			(at -2.732281 10.296375 270)
			(unlocked yes)
			(layer "F.SilkS")
			(hide yes)
			(effects
				(font
					(size 0.762 0.762)
					(thickness 0.2286)
				)
			)
		)
		(sheetname "USBUart_DipSelects")
		(sheetfile "USBUart_DipSelects.kicad_sch")
		(duplicate_pad_numbers_are_jumpers no)
		(pad "1" smd rect
			(at -0.45 0 90)
			(size 0.55 0.55)
			(layers "F.Cu" "F.Mask" "F.Paste")
			(net "GPS2_RX_FPGA")
		)
		(pad "2" smd rect
			(at 0.45 0 90)
			(size 0.55 0.55)
			(layers "F.Cu" "F.Mask" "F.Paste")
			(net "GPS2_RX")
		)
	)
	(footprint "Vault:RESC1608X55X25LL10T15"
		(layer "F.Cu")
		(at 131.4761 85.3162)
		(property "Reference" "R10"
			(at 0.4786 1.426931 0)
			(unlocked yes)
			(layer "F.SilkS")
			(effects
				(font
					(size 0.762 0.762)
					(thickness 0.2286)
				)
			)
		)
		(property "Value" "4.7K"
			(at -2.630671 2.57724 270)
			(unlocked yes)
			(layer "F.SilkS")
			(hide yes)
			(effects
				(font
					(size 0.762 0.762)
					(thickness 0.2286)
				)
			)
		)
		(sheetname "MAC")
		(sheetfile "MAC.kicad_sch")
		(duplicate_pad_numbers_are_jumpers no)
		(pad "1" smd rect
			(at -0.65 0 90)
			(size 0.8 0.6)
			(layers "F.Cu" "F.Mask" "F.Paste")
			(net "GND")
		)
		(pad "2" smd rect
			(at 0.65 0 90)
			(size 0.8 0.6)
			(layers "F.Cu" "F.Mask" "F.Paste")
			(net "FPGA_MAC_PPS_IN1-")
		)
	)
	(footprint "Vault:CAPC1608X87X45ML20T05"
		(layer "F.Cu")
		(at 197.3761 84.2786 -90)
		(property "Reference" "C31"
			(at 2.721395 -0.026921 90)
			(unlocked yes)
			(layer "F.SilkS")
			(effects
				(font
					(size 0.762 0.762)
					(thickness 0.2286)
				)
			)
		)
		(property "Value" "0.1uF"
			(at 2.069035 2.630671 270)
			(unlocked yes)
			(layer "F.SilkS")
			(hide yes)
			(effects
				(font
					(size 0.762 0.762)
					(thickness 0.2286)
				)
			)
		)
		(sheetname "GPS_IMU_SENSORS")
		(sheetfile "GPS_IMU_SENSORS.kicad_sch")
		(duplicate_pad_numbers_are_jumpers no)
		(pad "1" smd rect
			(at -0.7 0)
			(size 1.1 1.05)
			(layers "F.Cu" "F.Mask" "F.Paste")
			(net "GND")
		)
		(pad "2" smd rect
			(at 0.7 0)
			(size 1.1 1.05)
			(layers "F.Cu" "F.Mask" "F.Paste")
			(net "+3.3V")
		)
	)
	(footprint "Vault:FP-IHLP-2525EZ-FP_2_413x3-MFG"
		(layer "F.Cu")
		(at 218.8261 125.2162)
		(property "Reference" "L2"
			(at 3.706655 2.6 270)
			(unlocked yes)
			(layer "F.SilkS")
			(effects
				(font
					(size 0.762 0.762)
					(thickness 0.2286)
				)
				(justify left bottom)
			)
		)
		(property "Value" "2.2uH_10A"
			(at -11.1787 10.976845 0)
			(unlocked yes)
			(layer "F.SilkS")
			(hide yes)
			(effects
				(font
					(size 0.762 0.762)
					(thickness 0.2286)
				)
				(justify left bottom)
			)
		)
		(sheetname "POWER")
		(sheetfile "POWER.kicad_sch")
		(duplicate_pad_numbers_are_jumpers no)
		(fp_line
			(start -3.362 -3.362)
			(end 3.362 -3.362)
			(stroke
				(width 0.2)
				(type solid)
			)
			(layer "F.SilkS")
		)
		(fp_line
			(start -3.362 -2.0895)
			(end -3.362 -3.362)
			(stroke
				(width 0.2)
				(type solid)
			)
			(layer "F.SilkS")
		)
		(fp_line
			(start -3.362 3.362)
			(end -3.362 2.0895)
			(stroke
				(width 0.2)
				(type solid)
			)
			(layer "F.SilkS")
		)
		(fp_line
			(start -3.362 3.362)
			(end 3.362 3.362)
			(stroke
				(width 0.2)
				(type solid)
			)
			(layer "F.SilkS")
		)
		(fp_line
			(start 3.362 -2.0895)
			(end 3.362 -3.362)
			(stroke
				(width 0.2)
				(type solid)
			)
			(layer "F.SilkS")
		)
		(fp_line
			(start 3.362 3.362)
			(end 3.362 2.0895)
			(stroke
				(width 0.2)
				(type solid)
			)
			(layer "F.SilkS")
		)
		(fp_line
			(start -4.2275 -3.462)
			(end 4.2275 -3.462)
			(stroke
				(width 0.2)
				(type solid)
			)
			(layer "F.CrtYd")
		)
		(fp_line
			(start -4.2275 3.462)
			(end -4.2275 -3.462)
			(stroke
				(width 0.2)
				(type solid)
			)
			(layer "F.CrtYd")
		)
		(fp_line
			(start -4.2275 3.462)
			(end 4.2275 3.462)
			(stroke
				(width 0.2)
				(type solid)
			)
			(layer "F.CrtYd")
		)
		(fp_line
			(start 4.2275 3.462)
			(end 4.2275 -3.462)
			(stroke
				(width 0.2)
				(type solid)
			)
			(layer "F.CrtYd")
		)
		(fp_line
			(start -4.2275 -3.462)
			(end 4.2275 -3.462)
			(stroke
				(width 0.2)
				(type solid)
			)
			(layer "F.Fab")
		)
		(fp_line
			(start -4.2275 3.462)
			(end -4.2275 -3.462)
			(stroke
				(width 0.2)
				(type solid)
			)
			(layer "F.Fab")
		)
		(fp_line
			(start -4.2275 3.462)
			(end 4.2275 3.462)
			(stroke
				(width 0.2)
				(type solid)
			)
			(layer "F.Fab")
		)
		(fp_line
			(start -0.5 0)
			(end 0.5 0)
			(stroke
				(width 0.1)
				(type solid)
			)
			(layer "F.Fab")
		)
		(fp_line
			(start 0 0.5)
			(end 0 -0.5)
			(stroke
				(width 0.1)
				(type solid)
			)
			(layer "F.Fab")
		)
		(fp_line
			(start 4.2275 3.462)
			(end 4.2275 -3.462)
			(stroke
				(width 0.2)
				(type solid)
			)
			(layer "F.Fab")
		)
		(fp_text user "${REFERENCE}"
			(at -0.00001 0.10711 360)
			(unlocked yes)
			(layer "F.Fab")
			(effects
				(font
					(face "Arial")
					(size 0.63 0.63)
					(thickness 0.1)
				)
				(justify left bottom)
			)
		)
		(pad "1" smd rect
			(at -2.921 0)
			(size 2.413 3.429)
			(layers "F.Cu" "F.Mask" "F.Paste")
			(net "NetL2_1")
			(solder_mask_margin 0)
			(solder_paste_margin 0)
		)
		(pad "2" smd rect
			(at 2.921 0)
			(size 2.413 3.429)
			(layers "F.Cu" "F.Mask" "F.Paste")
			(net "P3V3_SENSE")
			(solder_mask_margin 0)
			(solder_paste_margin 0)
		)
	)
	(footprint "Vault:FP-SML-LX0603IW-TR-MFG"
		(layer "F.Cu")
		(at 167.2261 88.1162 -90)
		(property "Reference" "D25"
			(at -0.1286 1.673069 90)
			(unlocked yes)
			(layer "F.SilkS")
			(effects
				(font
					(size 0.762 0.762)
					(thickness 0.2286)
				)
			)
		)
		(property "Value" "SML-LX0603IW-TR"
			(at -3.519671 10.677135 180)
			(unlocked yes)
			(layer "F.SilkS")
			(hide yes)
			(effects
				(font
					(size 0.762 0.762)
					(thickness 0.2286)
				)
			)
		)
		(sheetname "USBUart_DipSelects")
		(sheetfile "USBUart_DipSelects.kicad_sch")
		(duplicate_pad_numbers_are_jumpers no)
		(fp_line
			(start 0.77933 0.73)
			(end -0.82067 0.73)
			(stroke
				(width 0.2)
				(type solid)
			)
			(layer "F.SilkS")
		)
		(fp_line
			(start 0.8 -0.75)
			(end -0.8 -0.75)
			(stroke
				(width 0.2)
				(type solid)
			)
			(layer "F.SilkS")
		)
		(fp_circle
			(center -1.725 0)
			(end -1.85 0)
			(stroke
				(width 0.25)
				(type solid)
			)
			(fill no)
			(layer "F.SilkS")
		)
		(fp_line
			(start -1.25 0.625)
			(end -1.25 -0.625)
			(stroke
				(width 0.2)
				(type solid)
			)
			(layer "F.CrtYd")
		)
		(fp_line
			(start 1.25 0.625)
			(end -1.25 0.625)
			(stroke
				(width 0.2)
				(type solid)
			)
			(layer "F.CrtYd")
		)
		(fp_line
			(start 1.25 0.625)
			(end 1.25 -0.625)
			(stroke
				(width 0.2)
				(type solid)
			)
			(layer "F.CrtYd")
		)
		(fp_line
			(start 1.25 -0.625)
			(end -1.25 -0.625)
			(stroke
				(width 0.2)
				(type solid)
			)
			(layer "F.CrtYd")
		)
		(fp_line
			(start -1.25 0.625)
			(end -1.25 -0.625)
			(stroke
				(width 0.2)
				(type solid)
			)
			(layer "F.Fab")
		)
		(fp_line
			(start 1.25 0.625)
			(end -1.25 0.625)
			(stroke
				(width 0.2)
				(type solid)
			)
			(layer "F.Fab")
		)
		(fp_line
			(start 1.25 0.625)
			(end 1.25 -0.625)
			(stroke
				(width 0.2)
				(type solid)
			)
			(layer "F.Fab")
		)
		(fp_line
			(start 0 0.5)
			(end 0 -0.5)
			(stroke
				(width 0.1)
				(type solid)
			)
			(layer "F.Fab")
		)
		(fp_line
			(start 0.5 0)
			(end -0.5 0)
			(stroke
				(width 0.1)
				(type solid)
			)
			(layer "F.Fab")
		)
		(fp_line
			(start 1.25 -0.625)
			(end -1.25 -0.625)
			(stroke
				(width 0.2)
				(type solid)
			)
			(layer "F.Fab")
		)
		(fp_text user "${REFERENCE}"
			(at 0 0.28425 270)
			(unlocked yes)
			(layer "F.Fab")
			(effects
				(font
					(face "Arial")
					(size 0.63 0.63)
					(thickness 0.1)
				)
				(justify left bottom)
			)
		)
		(pad "1" smd rect
			(at -0.75 0 270)
			(size 0.8 0.8)
			(layers "F.Cu" "F.Mask" "F.Paste")
			(net "NetD25_1")
			(solder_mask_margin 0)
			(solder_paste_margin 0)
		)
		(pad "2" smd rect
			(at 0.75 0 270)
			(size 0.8 0.8)
			(layers "F.Cu" "F.Mask" "F.Paste")
			(net "+3.3V")
			(solder_mask_margin 0)
			(solder_paste_margin 0)
		)
	)
	(footprint "Vault:CAPC1608X87X45ML20T05"
		(layer "F.Cu")
		(at 151.54502 80.89267 -90)
		(property "Reference" "C63"
			(at -0.27647 1.125575 90)
			(unlocked yes)
			(layer "F.SilkS")
			(effects
				(font
					(size 0.762 0.762)
					(thickness 0.2286)
				)
				(justify left bottom)
			)
		)
		(property "Value" "0.1uF"
			(at 1.829705 -4.27006 0)
			(unlocked yes)
			(layer "F.SilkS")
			(hide yes)
			(effects
				(font
					(size 0.762 0.762)
					(thickness 0.2286)
				)
				(justify left bottom)
			)
		)
		(sheetname "MAC")
		(sheetfile "MAC.kicad_sch")
		(duplicate_pad_numbers_are_jumpers no)
		(pad "1" smd rect
			(at -0.7 0)
			(size 1.1 1.05)
			(layers "F.Cu" "F.Mask" "F.Paste")
			(net "GND")
		)
		(pad "2" smd rect
			(at 0.7 0)
			(size 1.1 1.05)
			(layers "F.Cu" "F.Mask" "F.Paste")
			(net "MAC_VCC")
		)
	)
	(footprint "Vault:CAPC1608X87X45ML20T05"
		(layer "F.Cu")
		(at 84.1261 87.1162 90)
		(property "Reference" "C40"
			(at 0.4786 -3.473069 90)
			(unlocked yes)
			(layer "F.SilkS")
			(effects
				(font
					(size 0.762 0.762)
					(thickness 0.2286)
				)
			)
		)
		(property "Value" "0.1uF"
			(at 2.069035 2.630671 90)
			(unlocked yes)
			(layer "F.SilkS")
			(hide yes)
			(effects
				(font
					(size 0.762 0.762)
					(thickness 0.2286)
				)
			)
		)
		(sheetname "USER_IO_STATUS")
		(sheetfile "USER_IO_STATUS.kicad_sch")
		(duplicate_pad_numbers_are_jumpers no)
		(pad "1" smd rect
			(at -0.7 0 180)
			(size 1.1 1.05)
			(layers "F.Cu" "F.Mask" "F.Paste")
			(net "GND")
		)
		(pad "2" smd rect
			(at 0.7 0 180)
			(size 1.1 1.05)
			(layers "F.Cu" "F.Mask" "F.Paste")
			(net "+3.3V")
		)
	)
	(footprint "Vault:RESC1005X40X25LL05T05"
		(layer "F.Cu")
		(at 184.6261 82.8162)
		(property "Reference" "R54"
			(at -2.1714 -1.673079 0)
			(unlocked yes)
			(layer "F.SilkS")
			(effects
				(font
					(size 0.762 0.762)
					(thickness 0.2286)
				)
			)
		)
		(property "Value" "0_1%_0402"
			(at -2.579871 6.66536 270)
			(unlocked yes)
			(layer "F.SilkS")
			(hide yes)
			(effects
				(font
					(size 0.762 0.762)
					(thickness 0.2286)
				)
			)
		)
		(sheetname "GPS_IMU_SENSORS")
		(sheetfile "GPS_IMU_SENSORS.kicad_sch")
		(duplicate_pad_numbers_are_jumpers no)
		(pad "1" smd rect
			(at -0.4 0 90)
			(size 0.45 0.45)
			(layers "F.Cu" "F.Mask" "F.Paste")
			(net "PCIE_PERST")
		)
		(pad "2" smd rect
			(at 0.4 0 90)
			(size 0.45 0.45)
			(layers "F.Cu" "F.Mask" "F.Paste")
			(net "NetR52_1")
		)
	)
	(footprint "Vault:CAPC1608X87X45ML20T05"
		(layer "F.Cu")
		(at 232.8261 67.1162 180)
		(property "Reference" "C64"
			(at -0.4286 1.473079 0)
			(unlocked yes)
			(layer "F.SilkS")
			(effects
				(font
					(size 0.762 0.762)
					(thickness 0.2286)
				)
			)
		)
		(property "Value" "0.1uF"
			(at 2.069035 2.630671 180)
			(unlocked yes)
			(layer "F.SilkS")
			(hide yes)
			(effects
				(font
					(size 0.762 0.762)
					(thickness 0.2286)
				)
			)
		)
		(sheetname "GPS_IMU_SENSORS")
		(sheetfile "GPS_IMU_SENSORS.kicad_sch")
		(duplicate_pad_numbers_are_jumpers no)
		(pad "1" smd rect
			(at -0.7 0 270)
			(size 1.1 1.05)
			(layers "F.Cu" "F.Mask" "F.Paste")
			(net "GND")
		)
		(pad "2" smd rect
			(at 0.7 0 270)
			(size 1.1 1.05)
			(layers "F.Cu" "F.Mask" "F.Paste")
			(net "+5.0V")
		)
	)
	(footprint "Vault:FP-CL829-IPC_C"
		(layer "F.Cu")
		(at 231.8261 83.2162 180)
		(property "Reference" "C90"
			(at 1.8714 -0.026921 0)
			(unlocked yes)
			(layer "F.SilkS")
			(effects
				(font
					(size 0.762 0.762)
					(thickness 0.2286)
				)
			)
		)
		(property "Value" "4.7uF_16V_0402"
			(at -2.440151 9.864615 90)
			(unlocked yes)
			(layer "F.SilkS")
			(hide yes)
			(effects
				(font
					(size 0.762 0.762)
					(thickness 0.2286)
				)
			)
		)
		(sheetname "USBUart_DipSelects")
		(sheetfile "USBUart_DipSelects.kicad_sch")
		(duplicate_pad_numbers_are_jumpers no)
		(fp_line
			(start 0.63624 0.675)
			(end -0.63624 0.675)
			(stroke
				(width 0.2)
				(type solid)
			)
			(layer "F.SilkS")
		)
		(fp_line
			(start 0.63624 -0.675)
			(end -0.63624 -0.675)
			(stroke
				(width 0.2)
				(type solid)
			)
			(layer "F.SilkS")
		)
		(fp_line
			(start 0.73624 0.375)
			(end -0.73624 0.375)
			(stroke
				(width 0.2)
				(type solid)
			)
			(layer "F.CrtYd")
		)
		(fp_line
			(start 0.73624 -0.375)
			(end 0.73624 0.375)
			(stroke
				(width 0.2)
				(type solid)
			)
			(layer "F.CrtYd")
		)
		(fp_line
			(start 0.73624 -0.375)
			(end -0.73624 -0.375)
			(stroke
				(width 0.2)
				(type solid)
			)
			(layer "F.CrtYd")
		)
		(fp_line
			(start -0.73624 -0.375)
			(end -0.73624 0.375)
			(stroke
				(width 0.2)
				(type solid)
			)
			(layer "F.CrtYd")
		)
		(fp_line
			(start 0.73624 0.375)
			(end -0.73624 0.375)
			(stroke
				(width 0.2)
				(type solid)
			)
			(layer "F.Fab")
		)
		(fp_line
			(start 0.73624 -0.375)
			(end 0.73624 0.375)
			(stroke
				(width 0.2)
				(type solid)
			)
			(layer "F.Fab")
		)
		(fp_line
			(start 0.73624 -0.375)
			(end -0.73624 -0.375)
			(stroke
				(width 0.2)
				(type solid)
			)
			(layer "F.Fab")
		)
		(fp_line
			(start 0.5 0)
			(end -0.5 0)
			(stroke
				(width 0.1)
				(type solid)
			)
			(layer "F.Fab")
		)
		(fp_line
			(start 0.5 0)
			(end -0.5 0)
			(stroke
				(width 0.1)
				(type solid)
			)
			(layer "F.Fab")
		)
		(fp_line
			(start 0 -0.5)
			(end 0 0.5)
			(stroke
				(width 0.1)
				(type solid)
			)
			(layer "F.Fab")
		)
		(fp_line
			(start 0 -0.5)
			(end 0 0.5)
			(stroke
				(width 0.1)
				(type solid)
			)
			(layer "F.Fab")
		)
		(fp_line
			(start -0.73624 -0.375)
			(end -0.73624 0.375)
			(stroke
				(width 0.2)
				(type solid)
			)
			(layer "F.Fab")
		)
		(fp_text user "${REFERENCE}"
			(at 0 0.28425 180)
			(unlocked yes)
			(layer "F.Fab")
			(effects
				(font
					(face "Arial")
					(size 0.63 0.63)
					(thickness 0.1)
				)
				(justify left bottom)
			)
		)
		(pad "1" smd rect
			(at -0.37856 0 180)
			(size 0.51535 0.47247)
			(layers "F.Cu" "F.Mask" "F.Paste")
			(net "FTDI_VBUS")
			(solder_mask_margin 0)
			(solder_paste_margin 0)
		)
		(pad "2" smd rect
			(at 0.37856 0 180)
			(size 0.51535 0.47247)
			(layers "F.Cu" "F.Mask" "F.Paste")
			(net "GND")
			(solder_mask_margin 0)
			(solder_paste_margin 0)
		)
	)
)
